# T6G (Grand Teton) — schematic netlist excerpt (pin names and nets, part order shuffled) for the footprints in the layout excerpt that follows; sources: Cadence DE-HDL packaged netlist, KiCad conversion of 04192023_DAF0TMB3IC0_F0TG_MB_C_brd_V02_OCP.brd

J37  SCONN288_DDR506112002KQ  IO  pkg DDR288S_1-1VXC  page 109
  VIN_BULK0  = P12V_MEM_CPU1
  RFU0  = NC
  VIN_MGMT  = P3V3_AUX
  HSCL  = I3C_SPD_DDRL_CPU1_SCL
  HSDA  = I3C_SPD_DDRL_CPU1_SDA
  VSS0  = GND
  DQ0_A  = M_L_CPU1_SA_DQ<0>
  VSS1  = GND
  DQ1_A  = M_L_CPU1_SA_DQ<1>
  VSS2  = GND
  DQS0_A_T  = M_L_CPU1_SA_DQS_DP<0>
  DQS0_A_C  = M_L_CPU1_SA_DQS_DN<0>
  VSS3  = GND
  DQ4_A  = M_L_CPU1_SA_DQ<4>
  VSS4  = GND
  DQ5_A  = M_L_CPU1_SA_DQ<5>
  VSS5  = GND
  DQ8_A  = M_L_CPU1_SA_DQ<8>
  VSS6  = GND
  DQ9_A  = M_L_CPU1_SA_DQ<9>
  VSS7  = GND
  DQS1_A_T  = M_L_CPU1_SA_DQS_DP<1>
  DQS1_A_C  = M_L_CPU1_SA_DQS_DN<1>
  VSS8  = GND
  DQ12_A  = M_L_CPU1_SA_DQ<12>
  VSS9  = GND
  DQ13_A  = M_L_CPU1_SA_DQ<13>
  VSS10  = GND
  DQ16_A  = M_L_CPU1_SA_DQ<16>
  VSS11  = GND
  DQ17_A  = M_L_CPU1_SA_DQ<17>
  VSS12  = GND
  DQS2_A_T  = M_L_CPU1_SA_DQS_DP<2>
  DQS2_A_C  = M_L_CPU1_SA_DQS_DN<2>
  VSS13  = GND
  DQ20_A  = M_L_CPU1_SA_DQ<20>
  VSS14  = GND
  DQ21_A  = M_L_CPU1_SA_DQ<21>
  VSS15  = GND
  DQ24_A  = M_L_CPU1_SA_DQ<24>
  VSS16  = GND
  DQ25_A  = M_L_CPU1_SA_DQ<25>
  VSS17  = GND
  DQS3_A_T  = M_L_CPU1_SA_DQS_DP<3>
  DQS3_A_C  = M_L_CPU1_SA_DQS_DN<3>
  VSS18  = GND
  DQ28_A  = M_L_CPU1_SA_DQ<28>
  VSS19  = GND
  DQ29_A  = M_L_CPU1_SA_DQ<29>
  VSS20  = GND
  CB0_A  = M_L_CPU1_SA_CB<0>
  VSS21  = GND
  CB1_A  = M_L_CPU1_SA_CB<1>
  VSS22  = GND
  DQS4_A_T  = M_L_CPU1_SA_DQS_DP<4>
  DQS4_A_C  = M_L_CPU1_SA_DQS_DN<4>
  VSS23  = GND
  CB4_A  = M_L_CPU1_SA_CB<4>
  VSS24  = GND
  CB5_A  = M_L_CPU1_SA_CB<5>
  VSS25  = GND
  ALERT_N  = M_L_CPU1_ALERT_N
  VSS26  = GND
  CS0_A_N  = M_L_CPU1_SA_CS_N<0>
  VSS27  = GND
  CA0_A  = M_L_CPU1_SA_CA<0>
  VSS28  = GND
  CA2_A  = M_L_CPU1_SA_CA<2>
  VSS29  = GND
  CA4_A  = M_L_CPU1_SA_CA<4>
  VSS30  = GND
  CA6_A  = M_L_CPU1_SA_CA<6>
  VSS31  = GND
  PAR_A  = M_L_CPU1_SA_PAR
  VSS32  = GND
  CA0_B  = M_L_CPU1_SB_CA<0>
  VSS33  = GND
  CA2_B  = M_L_CPU1_SB_CA<2>
  VSS34  = GND
  CA4_B  = M_L_CPU1_SB_CA<4>
  VSS35  = GND
  CA6_B  = M_L_CPU1_SB_CA<6>
  VSS36  = GND
  CS0_B_N  = M_L_CPU1_SB_CS_N<0>
  VSS37  = GND
  \lbd||rsp_a_n\  = M_L_CPU1_SA_RSP<0>
  \lbs||rsp_b_n\  = M_L_CPU1_SB_RSP<0>
  VSS38  = GND
  CB4_B  = M_L_CPU1_SB_CB<4>
  VSS39  = GND
  CB5_B  = M_L_CPU1_SB_CB<5>
  VSS40  = GND
  \dqs9_b_t||tdqs9_b_t||dbi4_b_n\  = M_L_CPU1_SB_DQS_DP<9>
  \dqs9_b_c||tdqs9_b_c\  = M_L_CPU1_SB_DQS_DN<9>
  VSS41  = GND
  CB0_B  = M_L_CPU1_SB_CB<0>
  VSS42  = GND
  CB1_B  = M_L_CPU1_SB_CB<1>
  VSS43  = GND
  DQ0_B  = M_L_CPU1_SB_DQ<0>
  VSS44  = GND
  DQ1_B  = M_L_CPU1_SB_DQ<1>
  VSS45  = GND
  DQS0_B_T  = M_L_CPU1_SB_DQS_DP<0>
  DQS0_B_C  = M_L_CPU1_SB_DQS_DN<0>
  VSS46  = GND
  DQ4_B  = M_L_CPU1_SB_DQ<4>
  VSS47  = GND
  DQ5_B  = M_L_CPU1_SB_DQ<5>
  VSS48  = GND
  DQ8_B  = M_L_CPU1_SB_DQ<8>
  VSS49  = GND
  DQ9_B  = M_L_CPU1_SB_DQ<9>
  VSS50  = GND
  DQS1_B_T  = M_L_CPU1_SB_DQS_DP<1>
  DQS1_B_C  = M_L_CPU1_SB_DQS_DN<1>
  VSS51  = GND
  DQ12_B  = M_L_CPU1_SB_DQ<12>
  VSS52  = GND
  DQ13_B  = M_L_CPU1_SB_DQ<13>
  VSS53  = GND
  DQ16_B  = M_L_CPU1_SB_DQ<16>
  VSS54  = GND
  DQ17_B  = M_L_CPU1_SB_DQ<17>
  VSS55  = GND
  DQS2_B_T  = M_L_CPU1_SB_DQS_DP<2>
  DQS2_B_C  = M_L_CPU1_SB_DQS_DN<2>
  VSS56  = GND
  DQ20_B  = M_L_CPU1_SB_DQ<20>
  VSS57  = GND
  DQ21_B  = M_L_CPU1_SB_DQ<21>
  VSS58  = GND
  DQ24_B  = M_L_CPU1_SB_DQ<24>
  VSS59  = GND
  DQ25_B  = M_L_CPU1_SB_DQ<25>
  VSS60  = GND
  DQS3_B_T  = M_L_CPU1_SB_DQS_DP<3>
  DQS3_B_C  = M_L_CPU1_SB_DQS_DN<3>
  VSS61  = GND
  DQ28_B  = M_L_CPU1_SB_DQ<28>
  VSS62  = GND
  DQ29_B  = M_L_CPU1_SB_DQ<29>
  VSS63  = GND
  RFU1  = NC
  VIN_BULK1  = P12V_MEM_CPU1
  VIN_BULK2  = P12V_MEM_CPU1
  \pwr_good||fail_n\  = PWRGD_CHL_CPU1_DIMM
  HAS  = PD_CHL_CPU1_DIMM_SAA
  RFU2  = NC
  RFU3  = NC
  VSS64  = GND
  DQ2_A  = M_L_CPU1_SA_DQ<2>
  VSS65  = GND
  DQ3_A  = M_L_CPU1_SA_DQ<3>
  VSS66  = GND
  \dqs5_a_c||tdqs5_a_c||dqs5_a_t||tdqs5_a_t\  = M_L_CPU1_SA_DQS_DN<5>
  \dqs5_a_t||tdqs5_a_t\  = M_L_CPU1_SA_DQS_DP<5>
  VSS67  = GND
  DQ6_A  = M_L_CPU1_SA_DQ<6>
  VSS68  = GND
  DQ7_A  = M_L_CPU1_SA_DQ<7>
  VSS69  = GND
  DQ10_A  = M_L_CPU1_SA_DQ<10>
  VSS70  = GND
  DQ11_A  = M_L_CPU1_SA_DQ<11>
  VSS71  = GND
  \dqs6_a_c||tdqs6_a_c||dqs6_a_t||tdqs6_a_t\  = M_L_CPU1_SA_DQS_DN<6>
  \dqs6_a_t||tdqs6_a_t\  = M_L_CPU1_SA_DQS_DP<6>
  VSS72  = GND
  DQ14_A  = M_L_CPU1_SA_DQ<14>
  VSS73  = GND
  DQ15_A  = M_L_CPU1_SA_DQ<15>
  VSS74  = GND
  DQ18_A  = M_L_CPU1_SA_DQ<18>
  VSS75  = GND
  DQ19_A  = M_L_CPU1_SA_DQ<19>
  VSS76  = GND
  \dqs7_a_c||tdqs7_a_c\  = M_L_CPU1_SA_DQS_DN<7>
  \dqs7_a_t||tdqs7_a_t\  = M_L_CPU1_SA_DQS_DP<7>
  VSS77  = GND
  DQ22_A  = M_L_CPU1_SA_DQ<22>
  VSS78  = GND
  DQ23_A  = M_L_CPU1_SA_DQ<23>
  VSS79  = GND
  DQ26_A  = M_L_CPU1_SA_DQ<26>
  VSS80  = GND
  DQ27_A  = M_L_CPU1_SA_DQ<27>
  VSS81  = GND
  \dqs8_a_c||tdqs8_a_c\  = M_L_CPU1_SA_DQS_DN<8>
  \dqs8_a_t||tdqs8_a_t\  = M_L_CPU1_SA_DQS_DP<8>
  VSS82  = GND
  DQ30_A  = M_L_CPU1_SA_DQ<30>
  VSS83  = GND
  DQ31_A  = M_L_CPU1_SA_DQ<31>
  VSS84  = GND
  CB2_A  = M_L_CPU1_SA_CB<2>
  VSS85  = GND
  CB3_A  = M_L_CPU1_SA_CB<3>
  VSS86  = GND
  \dqs9_a_c||tdqs9_a_c\  = M_L_CPU1_SA_DQS_DN<9>
  \dqs9_a_t||tdqs9_a_t\  = M_L_CPU1_SA_DQS_DP<9>
  VSS87  = GND
  CB6_A  = M_L_CPU1_SA_CB<6>
  VSS88  = GND
  CB7_A  = M_L_CPU1_SA_CB<7>
  VSS89  = GND
  RESET_N  = M_L_CPU1_RESET_N
  VSS90  = GND
  CS1_A_N  = M_L_CPU1_SA_CS_N<1>
  VSS91  = GND
  CA1_A  = M_L_CPU1_SA_CA<1>
  VSS92  = GND
  CA3_A  = M_L_CPU1_SA_CA<3>
  VSS93  = GND
  CA5_A  = M_L_CPU1_SA_CA<5>
  VSS94  = GND
  CK_T  = M_L_CPU1_CLK_DP<0>
  CK_C  = M_L_CPU1_CLK_DN<0>
  VSS95  = GND
  RFU4  = NC
  CA1_B  = M_L_CPU1_SB_CA<1>
  VSS96  = GND
  CA3_B  = M_L_CPU1_SB_CA<3>
  VSS97  = GND
  CA5_B  = M_L_CPU1_SB_CA<5>
  VSS98  = GND
  PAR_B  = M_L_CPU1_SB_PAR
  VSS99  = GND
  CS1_B_N  = M_L_CPU1_SB_CS_N<1>
  VSS100  = GND
  RFU5  = NC
  RFU6  = NC
  VSS101  = GND
  CB6_B  = M_L_CPU1_SB_CB<6>
  VSS102  = GND
  CB7_B  = M_L_CPU1_SB_CB<7>
  VSS103  = GND
  DQS4_B_C  = M_L_CPU1_SB_DQS_DN<4>
  DQS4_B_T  = M_L_CPU1_SB_DQS_DP<4>
  VSS104  = GND
  CB2_B  = M_L_CPU1_SB_CB<2>
  VSS105  = GND
  CB3_B  = M_L_CPU1_SB_CB<3>
  VSS106  = GND
  DQ2_B  = M_L_CPU1_SB_DQ<2>
  VSS107  = GND
  DQ3_B  = M_L_CPU1_SB_DQ<3>
  VSS108  = GND
  \dqs5_b_c||tdqs5_b_c\  = M_L_CPU1_SB_DQS_DN<5>
  \dqs5_b_t||tdqs5_b_t\  = M_L_CPU1_SB_DQS_DP<5>
  VSS109  = GND
  DQ6_B  = M_L_CPU1_SB_DQ<6>
  VSS110  = GND
  DQ7_B  = M_L_CPU1_SB_DQ<7>
  VSS111  = GND
  DQ10_B  = M_L_CPU1_SB_DQ<10>
  VSS112  = GND
  DQ11_B  = M_L_CPU1_SB_DQ<11>
  VSS113  = GND
  \dqs6_b_c||tdqs6_b_c\  = M_L_CPU1_SB_DQS_DN<6>
  \dqs6_b_t||tdqs6_b_t\  = M_L_CPU1_SB_DQS_DP<6>
  VSS114  = GND
  DQ14_B  = M_L_CPU1_SB_DQ<14>
  VSS115  = GND
  DQ15_B  = M_L_CPU1_SB_DQ<15>
  VSS116  = GND
  DQ18_B  = M_L_CPU1_SB_DQ<18>
  VSS117  = GND
  DQ19_B  = M_L_CPU1_SB_DQ<19>
  VSS118  = GND
  \dqs7_b_c||tdqs7_b_c\  = M_L_CPU1_SB_DQS_DN<7>
  \dqs7_b_t||tdqs7_b_t\  = M_L_CPU1_SB_DQS_DP<7>
  VSS119  = GND
  DQ22_B  = M_L_CPU1_SB_DQ<22>
  VSS120  = GND
  DQ23_B  = M_L_CPU1_SB_DQ<23>
  VSS121  = GND
  DQ26_B  = M_L_CPU1_SB_DQ<26>
  VSS122  = GND
  DQ27_B  = M_L_CPU1_SB_DQ<27>
  VSS123  = GND
  \dqs8_b_c||tdqs8_b_c\  = M_L_CPU1_SB_DQS_DN<8>
  \dqs8_b_t||tdqs8_b_t\  = M_L_CPU1_SB_DQS_DP<8>
  VSS124  = GND
  DQ30_B  = M_L_CPU1_SB_DQ<30>
  VSS125  = GND
  DQ31_B  = M_L_CPU1_SB_DQ<31>
  VSS126  = GND
  G1  = GND
  G2  = GND
  G3  = GND

(kicad_pcb
	(version 20260206)
	(generator "pcbnew")
	(generator_version "10.0")
	(general
		(thickness 1.6)
		(legacy_teardrops no)
	)
	(paper "A4")
	(title_block
		(title "04192023_DAF0TMB3IC0_F0TG_MB_C_brd_V02_OCP.brd")
		(comment 1 "Grand Teton / footprint 34 of 8354 (J37), pads 47-92 of 291")
	)
	(layers
		(0 "F.Cu" signal "TOP")
		(4 "In1.Cu" signal "GND")
		(6 "In2.Cu" signal "IN1")
		(8 "In3.Cu" signal "GND1")
		(10 "In4.Cu" signal "IN2")
		(12 "In5.Cu" signal "GND2")
		(14 "In6.Cu" signal "IN3")
		(16 "In7.Cu" signal "GND3")
		(18 "In8.Cu" signal "VCC")
		(20 "In9.Cu" signal "VCC1")
		(22 "In10.Cu" signal "GND4")
		(24 "In11.Cu" signal "IN4")
		(26 "In12.Cu" signal "GND5")
		(28 "In13.Cu" signal "IN5")
		(30 "In14.Cu" signal "GND6")
		(32 "In15.Cu" signal "IN6")
		(34 "In16.Cu" signal "GND7")
		(2 "B.Cu" signal "BOTTOM")
		(9 "F.Adhes" user "F.Adhesive")
		(11 "B.Adhes" user "B.Adhesive")
		(13 "F.Paste" user "Package Geometry/Pastemask Top")
		(15 "B.Paste" user "Package Geometry/Pastemask Bottom")
		(5 "F.SilkS" user "Ref Des/Silkscreen Top")
		(7 "B.SilkS" user "Ref Des/Silkscreen Bottom")
		(1 "F.Mask" user "Board Geometry/Soldermask Top")
		(3 "B.Mask" user "Board Geometry/Soldermask Bottom")
		(17 "Dwgs.User" user "User.Drawings")
		(19 "Cmts.User" user "User.Comments")
		(21 "Eco1.User" user "User.Eco1")
		(23 "Eco2.User" user "User.Eco2")
		(25 "Edge.Cuts" user "Board Geometry/Outline")
		(27 "Margin" user)
		(31 "F.CrtYd" user "Package Geometry/Place Bound Top")
		(29 "B.CrtYd" user "Package Geometry/Place Bound Bottom")
		(35 "F.Fab" user "Ref Des/Assembly Top")
		(33 "B.Fab" user "Ref Des/Assembly Bottom")
	)
	(footprint ""
		(layer "F.Cu")
		(at 204.197966 -255.560322 180)
		(property "Reference" "J37"
			(at 2.8702 -81.730088 0)
			(unlocked yes)
			(layer "F.SilkS")
			(effects
				(font
					(size 0.7874 0.5842)
					(thickness 0.1524)
				)
			)
		)
		(property "Value" ""
			(at 0 0 180)
			(layer "F.Fab")
			(effects
				(font
					(size 1.27 1.27)
				)
			)
		)
		(duplicate_pad_numbers_are_jumpers no)
		(pad "47" smd rect
			(at -2.050034 -24.224996 90)
			(size 0.519938 1.4986)
			(layers "F.Cu" "F.Mask" "F.Paste")
			(net "M_L_CPU1_SA_DQ<28>")
		)
		(pad "48" smd rect
			(at -2.050034 -23.375112 90)
			(size 0.519938 1.4986)
			(layers "F.Cu" "F.Mask" "F.Paste")
			(net "GND")
		)
		(pad "49" smd rect
			(at -2.050034 -22.524974 90)
			(size 0.519938 1.4986)
			(layers "F.Cu" "F.Mask" "F.Paste")
			(net "M_L_CPU1_SA_DQ<29>")
		)
		(pad "50" smd rect
			(at -2.050034 -21.67509 90)
			(size 0.519938 1.4986)
			(layers "F.Cu" "F.Mask" "F.Paste")
			(net "GND")
		)
		(pad "51" smd rect
			(at -2.050034 -20.824952 90)
			(size 0.519938 1.4986)
			(layers "F.Cu" "F.Mask" "F.Paste")
			(net "M_L_CPU1_SA_CB<0>")
		)
		(pad "52" smd rect
			(at -2.050034 -19.975068 90)
			(size 0.519938 1.4986)
			(layers "F.Cu" "F.Mask" "F.Paste")
			(net "GND")
		)
		(pad "53" smd rect
			(at -2.050034 -19.12493 90)
			(size 0.519938 1.4986)
			(layers "F.Cu" "F.Mask" "F.Paste")
			(net "M_L_CPU1_SA_CB<1>")
		)
		(pad "54" smd rect
			(at -2.050034 -18.275046 90)
			(size 0.519938 1.4986)
			(layers "F.Cu" "F.Mask" "F.Paste")
			(net "GND")
		)
		(pad "55" smd rect
			(at -2.050034 -17.424908 90)
			(size 0.519938 1.4986)
			(layers "F.Cu" "F.Mask" "F.Paste")
			(net "M_L_CPU1_SA_DQS_DP<4>")
		)
		(pad "56" smd rect
			(at -2.050034 -16.575024 90)
			(size 0.519938 1.4986)
			(layers "F.Cu" "F.Mask" "F.Paste")
			(net "M_L_CPU1_SA_DQS_DN<4>")
		)
		(pad "57" smd rect
			(at -2.050034 -15.724886 90)
			(size 0.519938 1.4986)
			(layers "F.Cu" "F.Mask" "F.Paste")
			(net "GND")
		)
		(pad "58" smd rect
			(at -2.050034 -14.875002 90)
			(size 0.519938 1.4986)
			(layers "F.Cu" "F.Mask" "F.Paste")
			(net "M_L_CPU1_SA_CB<4>")
		)
		(pad "59" smd rect
			(at -2.050034 -14.025118 90)
			(size 0.519938 1.4986)
			(layers "F.Cu" "F.Mask" "F.Paste")
			(net "GND")
		)
		(pad "60" smd rect
			(at -2.050034 -13.17498 90)
			(size 0.519938 1.4986)
			(layers "F.Cu" "F.Mask" "F.Paste")
			(net "M_L_CPU1_SA_CB<5>")
		)
		(pad "61" smd rect
			(at -2.050034 -12.325096 90)
			(size 0.519938 1.4986)
			(layers "F.Cu" "F.Mask" "F.Paste")
			(net "GND")
		)
		(pad "62" smd rect
			(at -2.050034 -11.474958 90)
			(size 0.519938 1.4986)
			(layers "F.Cu" "F.Mask" "F.Paste")
			(net "M_L_CPU1_ALERT_N")
		)
		(pad "63" smd rect
			(at -2.050034 -10.625074 90)
			(size 0.519938 1.4986)
			(layers "F.Cu" "F.Mask" "F.Paste")
			(net "GND")
		)
		(pad "64" smd rect
			(at -2.050034 -9.774936 90)
			(size 0.519938 1.4986)
			(layers "F.Cu" "F.Mask" "F.Paste")
			(net "M_L_CPU1_SA_CS_N<0>")
		)
		(pad "65" smd rect
			(at -2.050034 -8.925052 90)
			(size 0.519938 1.4986)
			(layers "F.Cu" "F.Mask" "F.Paste")
			(net "GND")
		)
		(pad "66" smd rect
			(at -2.050034 -8.074914 90)
			(size 0.519938 1.4986)
			(layers "F.Cu" "F.Mask" "F.Paste")
			(net "M_L_CPU1_SA_CA<0>")
		)
		(pad "67" smd rect
			(at -2.050034 -7.22503 90)
			(size 0.519938 1.4986)
			(layers "F.Cu" "F.Mask" "F.Paste")
			(net "GND")
		)
		(pad "68" smd rect
			(at -2.050034 -6.374892 90)
			(size 0.519938 1.4986)
			(layers "F.Cu" "F.Mask" "F.Paste")
			(net "M_L_CPU1_SA_CA<2>")
		)
		(pad "69" smd rect
			(at -2.050034 -5.525008 90)
			(size 0.519938 1.4986)
			(layers "F.Cu" "F.Mask" "F.Paste")
			(net "GND")
		)
		(pad "70" smd rect
			(at -2.050034 -4.675124 90)
			(size 0.519938 1.4986)
			(layers "F.Cu" "F.Mask" "F.Paste")
			(net "M_L_CPU1_SA_CA<4>")
		)
		(pad "71" smd rect
			(at -2.050034 -3.824986 90)
			(size 0.519938 1.4986)
			(layers "F.Cu" "F.Mask" "F.Paste")
			(net "GND")
		)
		(pad "72" smd rect
			(at -2.050034 -2.975102 90)
			(size 0.519938 1.4986)
			(layers "F.Cu" "F.Mask" "F.Paste")
			(net "M_L_CPU1_SA_CA<6>")
		)
		(pad "73" smd rect
			(at -2.050034 -2.124964 90)
			(size 0.519938 1.4986)
			(layers "F.Cu" "F.Mask" "F.Paste")
			(net "GND")
		)
		(pad "74" smd rect
			(at -2.050034 -1.27508 90)
			(size 0.519938 1.4986)
			(layers "F.Cu" "F.Mask" "F.Paste")
			(net "M_L_CPU1_SA_PAR")
		)
		(pad "75" smd rect
			(at -2.050034 -0.424942 90)
			(size 0.519938 1.4986)
			(layers "F.Cu" "F.Mask" "F.Paste")
			(net "GND")
		)
		(pad "76" smd rect
			(at -2.050034 5.525008 90)
			(size 0.519938 1.4986)
			(layers "F.Cu" "F.Mask" "F.Paste")
			(net "M_L_CPU1_SB_CA<0>")
		)
		(pad "77" smd rect
			(at -2.050034 6.374892 90)
			(size 0.519938 1.4986)
			(layers "F.Cu" "F.Mask" "F.Paste")
			(net "GND")
		)
		(pad "78" smd rect
			(at -2.050034 7.22503 90)
			(size 0.519938 1.4986)
			(layers "F.Cu" "F.Mask" "F.Paste")
			(net "M_L_CPU1_SB_CA<2>")
		)
		(pad "79" smd rect
			(at -2.050034 8.074914 90)
			(size 0.519938 1.4986)
			(layers "F.Cu" "F.Mask" "F.Paste")
			(net "GND")
		)
		(pad "80" smd rect
			(at -2.050034 8.925052 90)
			(size 0.519938 1.4986)
			(layers "F.Cu" "F.Mask" "F.Paste")
			(net "M_L_CPU1_SB_CA<4>")
		)
		(pad "81" smd rect
			(at -2.050034 9.774936 90)
			(size 0.519938 1.4986)
			(layers "F.Cu" "F.Mask" "F.Paste")
			(net "GND")
		)
		(pad "82" smd rect
			(at -2.050034 10.625074 90)
			(size 0.519938 1.4986)
			(layers "F.Cu" "F.Mask" "F.Paste")
			(net "M_L_CPU1_SB_CA<6>")
		)
		(pad "83" smd rect
			(at -2.050034 11.474958 90)
			(size 0.519938 1.4986)
			(layers "F.Cu" "F.Mask" "F.Paste")
			(net "GND")
		)
		(pad "84" smd rect
			(at -2.050034 12.325096 90)
			(size 0.519938 1.4986)
			(layers "F.Cu" "F.Mask" "F.Paste")
			(net "M_L_CPU1_SB_CS_N<0>")
		)
		(pad "85" smd rect
			(at -2.050034 13.17498 90)
			(size 0.519938 1.4986)
			(layers "F.Cu" "F.Mask" "F.Paste")
			(net "GND")
		)
		(pad "86" smd rect
			(at -2.050034 14.025118 90)
			(size 0.519938 1.4986)
			(layers "F.Cu" "F.Mask" "F.Paste")
			(net "M_L_CPU1_SA_RSP<0>")
		)
		(pad "87" smd rect
			(at -2.050034 14.875002 90)
			(size 0.519938 1.4986)
			(layers "F.Cu" "F.Mask" "F.Paste")
			(net "M_L_CPU1_SB_RSP<0>")
		)
		(pad "88" smd rect
			(at -2.050034 15.724886 90)
			(size 0.519938 1.4986)
			(layers "F.Cu" "F.Mask" "F.Paste")
			(net "GND")
		)
		(pad "89" smd rect
			(at -2.050034 16.575024 90)
			(size 0.519938 1.4986)
			(layers "F.Cu" "F.Mask" "F.Paste")
			(net "M_L_CPU1_SB_CB<4>")
		)
		(pad "90" smd rect
			(at -2.050034 17.424908 90)
			(size 0.519938 1.4986)
			(layers "F.Cu" "F.Mask" "F.Paste")
			(net "GND")
		)
		(pad "91" smd rect
			(at -2.050034 18.275046 90)
			(size 0.519938 1.4986)
			(layers "F.Cu" "F.Mask" "F.Paste")
			(net "M_L_CPU1_SB_CB<5>")
		)
		(pad "92" smd rect
			(at -2.050034 19.12493 90)
			(size 0.519938 1.4986)
			(layers "F.Cu" "F.Mask" "F.Paste")
			(net "GND")
		)
	)
)
